FILE_TYPE = CONNECTIVITY;
{Allegro Design Entry HDL 17.2-2016 S081 (4005846) 1/11/2022}
"PAGE_NUMBER" = 124;
0"NC";
END.
